(kicad_pcb
	(version 20260206)
	(generator "pcbnew")
	(generator_version "10.0")
	(general
		(thickness 1.6)
		(legacy_teardrops no)
	)
	(paper "A4")
	(title_block
		(title "04192023_DAF0TMB3IC0_F0TG_MB_C_brd_V02_OCP.brd")
		(comment 1 "Grand Teton / footprints 6033-6040 of 8354")
	)
	(layers
		(0 "F.Cu" signal "TOP")
		(4 "In1.Cu" signal "GND")
		(6 "In2.Cu" signal "IN1")
		(8 "In3.Cu" signal "GND1")
		(10 "In4.Cu" signal "IN2")
		(12 "In5.Cu" signal "GND2")
		(14 "In6.Cu" signal "IN3")
		(16 "In7.Cu" signal "GND3")
		(18 "In8.Cu" signal "VCC")
		(20 "In9.Cu" signal "VCC1")
		(22 "In10.Cu" signal "GND4")
		(24 "In11.Cu" signal "IN4")
		(26 "In12.Cu" signal "GND5")
		(28 "In13.Cu" signal "IN5")
		(30 "In14.Cu" signal "GND6")
		(32 "In15.Cu" signal "IN6")
		(34 "In16.Cu" signal "GND7")
		(2 "B.Cu" signal "BOTTOM")
		(9 "F.Adhes" user "F.Adhesive")
		(11 "B.Adhes" user "B.Adhesive")
		(13 "F.Paste" user "Package Geometry/Pastemask Top")
		(15 "B.Paste" user "Package Geometry/Pastemask Bottom")
		(5 "F.SilkS" user "Ref Des/Silkscreen Top")
		(7 "B.SilkS" user "Ref Des/Silkscreen Bottom")
		(1 "F.Mask" user "Board Geometry/Soldermask Top")
		(3 "B.Mask" user "Board Geometry/Soldermask Bottom")
		(17 "Dwgs.User" user "User.Drawings")
		(19 "Cmts.User" user "User.Comments")
		(21 "Eco1.User" user "User.Eco1")
		(23 "Eco2.User" user "User.Eco2")
		(25 "Edge.Cuts" user "Board Geometry/Outline")
		(27 "Margin" user)
		(31 "F.CrtYd" user "Package Geometry/Place Bound Top")
		(29 "B.CrtYd" user "Package Geometry/Place Bound Bottom")
		(35 "F.Fab" user "Ref Des/Assembly Top")
		(33 "B.Fab" user "Ref Des/Assembly Bottom")
	)
	(footprint ""
		(layer "B.Cu")
		(at 112.425988 -256.012442 -90)
		(property "Reference" "C3901"
			(at 0 0 90)
			(layer "B.SilkS")
			(hide yes)
			(effects
				(font
					(size 1.27 1.27)
				)
				(justify mirror)
			)
		)
		(property "Value" ""
			(at 0 0 90)
			(layer "B.Fab")
			(effects
				(font
					(size 1.27 1.27)
				)
				(justify mirror)
			)
		)
		(duplicate_pad_numbers_are_jumpers no)
		(fp_line
			(start -0.7874 0.4064)
			(end 0.7874 0.4064)
			(stroke
				(width 0.1524)
				(type default)
			)
			(layer "B.SilkS")
		)
		(fp_line
			(start 0.7874 0.4064)
			(end 0.7874 -0.4064)
			(stroke
				(width 0.1524)
				(type default)
			)
			(layer "B.SilkS")
		)
		(fp_line
			(start -0.7874 -0.4064)
			(end -0.7874 0.4064)
			(stroke
				(width 0.1524)
				(type default)
			)
			(layer "B.SilkS")
		)
		(fp_line
			(start 0.7874 -0.4064)
			(end -0.7874 -0.4064)
			(stroke
				(width 0.1524)
				(type default)
			)
			(layer "B.SilkS")
		)
		(fp_line
			(start -0.67945 0.3048)
			(end -0.120396 0.3048)
			(stroke
				(width 0.1)
				(type default)
			)
			(layer "B.Fab")
		)
		(fp_line
			(start -0.120396 0.3048)
			(end -0.120396 0.2794)
			(stroke
				(width 0.1)
				(type default)
			)
			(layer "B.Fab")
		)
		(fp_line
			(start 0.12065 0.3048)
			(end 0.67945 0.3048)
			(stroke
				(width 0.1)
				(type default)
			)
			(layer "B.Fab")
		)
		(fp_line
			(start 0.67945 0.3048)
			(end 0.67945 -0.305054)
			(stroke
				(width 0.1)
				(type default)
			)
			(layer "B.Fab")
		)
		(fp_line
			(start -0.120396 0.2794)
			(end 0.12065 0.2794)
			(stroke
				(width 0.1)
				(type default)
			)
			(layer "B.Fab")
		)
		(fp_line
			(start 0.12065 0.2794)
			(end 0.12065 0.3048)
			(stroke
				(width 0.1)
				(type default)
			)
			(layer "B.Fab")
		)
		(fp_line
			(start -0.12065 -0.2794)
			(end -0.12065 -0.3048)
			(stroke
				(width 0.1)
				(type default)
			)
			(layer "B.Fab")
		)
		(fp_line
			(start 0.12065 -0.2794)
			(end -0.12065 -0.2794)
			(stroke
				(width 0.1)
				(type default)
			)
			(layer "B.Fab")
		)
		(fp_line
			(start -0.67945 -0.3048)
			(end -0.67945 0.3048)
			(stroke
				(width 0.1)
				(type default)
			)
			(layer "B.Fab")
		)
		(fp_line
			(start -0.12065 -0.3048)
			(end -0.67945 -0.3048)
			(stroke
				(width 0.1)
				(type default)
			)
			(layer "B.Fab")
		)
		(fp_line
			(start 0.12065 -0.305054)
			(end 0.12065 -0.2794)
			(stroke
				(width 0.1)
				(type default)
			)
			(layer "B.Fab")
		)
		(fp_line
			(start 0.67945 -0.305054)
			(end 0.12065 -0.305054)
			(stroke
				(width 0.1)
				(type default)
			)
			(layer "B.Fab")
		)
		(pad "1" smd circle
			(at 0.40005 0 90)
			(size 0 0)
			(layers "B.Cu" "B.Mask" "B.Paste")
			(net "PVDDCR_SOC_P1")
		)
		(pad "2" smd circle
			(at -0.40005 0 90)
			(size 0 0)
			(layers "B.Cu" "B.Mask" "B.Paste")
			(net "GND")
		)
	)
	(footprint ""
		(layer "B.Cu")
		(at 286.952182 -346.784168 90)
		(property "Reference" "PC184_3"
			(at 0 0 90)
			(layer "B.SilkS")
			(hide yes)
			(effects
				(font
					(size 1.27 1.27)
				)
				(justify mirror)
			)
		)
		(property "Value" ""
			(at 0 0 90)
			(layer "B.Fab")
			(effects
				(font
					(size 1.27 1.27)
				)
				(justify mirror)
			)
		)
		(duplicate_pad_numbers_are_jumpers no)
		(fp_line
			(start 1.524 -0.762)
			(end -1.524 -0.762)
			(stroke
				(width 0.1524)
				(type default)
			)
			(layer "B.SilkS")
		)
		(fp_line
			(start -1.524 -0.762)
			(end -1.524 0.762)
			(stroke
				(width 0.1524)
				(type default)
			)
			(layer "B.SilkS")
		)
		(fp_line
			(start 1.524 0.762)
			(end 1.524 -0.762)
			(stroke
				(width 0.1524)
				(type default)
			)
			(layer "B.SilkS")
		)
		(fp_line
			(start -1.524 0.762)
			(end 1.524 0.762)
			(stroke
				(width 0.1524)
				(type default)
			)
			(layer "B.SilkS")
		)
		(fp_line
			(start 1.1049 -0.724916)
			(end 1.1049 0.724916)
			(stroke
				(width 0.1)
				(type default)
			)
			(layer "B.Fab")
		)
		(fp_line
			(start -1.1049 -0.724916)
			(end 1.1049 -0.724916)
			(stroke
				(width 0.1)
				(type default)
			)
			(layer "B.Fab")
		)
		(fp_line
			(start 1.1049 0.724916)
			(end -1.1049 0.724916)
			(stroke
				(width 0.1)
				(type default)
			)
			(layer "B.Fab")
		)
		(fp_line
			(start -1.1049 0.724916)
			(end -1.1049 -0.724916)
			(stroke
				(width 0.1)
				(type default)
			)
			(layer "B.Fab")
		)
		(pad "1" smd rect
			(at 0.889 0 90)
			(size 1.016 1.27)
			(layers "B.Cu" "B.Mask" "B.Paste")
			(net "SW_P12V_AUX_PVDDIO_P0_FLT")
		)
		(pad "2" smd rect
			(at -0.889 0 90)
			(size 1.016 1.27)
			(layers "B.Cu" "B.Mask" "B.Paste")
			(net "GND")
		)
	)
	(footprint ""
		(layer "B.Cu")
		(at 420.667688 -194.88531 180)
		(property "Reference" "R765"
			(at 0 0 0)
			(layer "B.SilkS")
			(hide yes)
			(effects
				(font
					(size 1.27 1.27)
				)
				(justify mirror)
			)
		)
		(property "Value" ""
			(at 0 0 0)
			(layer "B.Fab")
			(effects
				(font
					(size 1.27 1.27)
				)
				(justify mirror)
			)
		)
		(duplicate_pad_numbers_are_jumpers no)
		(fp_line
			(start 0.7874 0.4064)
			(end 0.7874 -0.4064)
			(stroke
				(width 0.1524)
				(type default)
			)
			(layer "B.SilkS")
		)
		(fp_line
			(start 0.7874 -0.4064)
			(end -0.7874 -0.4064)
			(stroke
				(width 0.1524)
				(type default)
			)
			(layer "B.SilkS")
		)
		(fp_line
			(start -0.7874 0.4064)
			(end 0.7874 0.4064)
			(stroke
				(width 0.1524)
				(type default)
			)
			(layer "B.SilkS")
		)
		(fp_line
			(start -0.7874 -0.4064)
			(end -0.7874 0.4064)
			(stroke
				(width 0.1524)
				(type default)
			)
			(layer "B.SilkS")
		)
		(fp_line
			(start 0.67945 0.3048)
			(end 0.67945 -0.305054)
			(stroke
				(width 0.1)
				(type default)
			)
			(layer "B.Fab")
		)
		(fp_line
			(start 0.67945 -0.305054)
			(end 0.12065 -0.305054)
			(stroke
				(width 0.1)
				(type default)
			)
			(layer "B.Fab")
		)
		(fp_line
			(start 0.12065 0.3048)
			(end 0.67945 0.3048)
			(stroke
				(width 0.1)
				(type default)
			)
			(layer "B.Fab")
		)
		(fp_line
			(start 0.12065 0.2794)
			(end 0.12065 0.3048)
			(stroke
				(width 0.1)
				(type default)
			)
			(layer "B.Fab")
		)
		(fp_line
			(start 0.12065 -0.2794)
			(end -0.12065 -0.2794)
			(stroke
				(width 0.1)
				(type default)
			)
			(layer "B.Fab")
		)
		(fp_line
			(start 0.12065 -0.305054)
			(end 0.12065 -0.2794)
			(stroke
				(width 0.1)
				(type default)
			)
			(layer "B.Fab")
		)
		(fp_line
			(start -0.120396 0.3048)
			(end -0.120396 0.2794)
			(stroke
				(width 0.1)
				(type default)
			)
			(layer "B.Fab")
		)
		(fp_line
			(start -0.120396 0.2794)
			(end 0.12065 0.2794)
			(stroke
				(width 0.1)
				(type default)
			)
			(layer "B.Fab")
		)
		(fp_line
			(start -0.12065 -0.2794)
			(end -0.12065 -0.3048)
			(stroke
				(width 0.1)
				(type default)
			)
			(layer "B.Fab")
		)
		(fp_line
			(start -0.12065 -0.3048)
			(end -0.67945 -0.3048)
			(stroke
				(width 0.1)
				(type default)
			)
			(layer "B.Fab")
		)
		(fp_line
			(start -0.67945 0.3048)
			(end -0.120396 0.3048)
			(stroke
				(width 0.1)
				(type default)
			)
			(layer "B.Fab")
		)
		(fp_line
			(start -0.67945 -0.3048)
			(end -0.67945 0.3048)
			(stroke
				(width 0.1)
				(type default)
			)
			(layer "B.Fab")
		)
		(pad "1" smd circle
			(at 0.40005 0)
			(size 0 0)
			(layers "B.Cu" "B.Mask" "B.Paste")
			(net "PD_CHH_CPU0_DIMM_SAA")
		)
		(pad "2" smd circle
			(at -0.40005 0)
			(size 0 0)
			(layers "B.Cu" "B.Mask" "B.Paste")
			(net "GND")
		)
	)
	(footprint ""
		(layer "B.Cu")
		(at 196.977 -112.395)
		(property "Reference" "R6854"
			(at 0 0 0)
			(layer "B.SilkS")
			(hide yes)
			(effects
				(font
					(size 1.27 1.27)
				)
				(justify mirror)
			)
		)
		(property "Value" ""
			(at 0 0 0)
			(layer "B.Fab")
			(effects
				(font
					(size 1.27 1.27)
				)
				(justify mirror)
			)
		)
		(duplicate_pad_numbers_are_jumpers no)
		(fp_line
			(start -0.7874 -0.4064)
			(end -0.7874 0.4064)
			(stroke
				(width 0.1524)
				(type default)
			)
			(layer "B.SilkS")
		)
		(fp_line
			(start -0.7874 0.4064)
			(end 0.7874 0.4064)
			(stroke
				(width 0.1524)
				(type default)
			)
			(layer "B.SilkS")
		)
		(fp_line
			(start 0.7874 -0.4064)
			(end -0.7874 -0.4064)
			(stroke
				(width 0.1524)
				(type default)
			)
			(layer "B.SilkS")
		)
		(fp_line
			(start 0.7874 0.4064)
			(end 0.7874 -0.4064)
			(stroke
				(width 0.1524)
				(type default)
			)
			(layer "B.SilkS")
		)
		(fp_line
			(start -0.67945 -0.3048)
			(end -0.67945 0.3048)
			(stroke
				(width 0.1)
				(type default)
			)
			(layer "B.Fab")
		)
		(fp_line
			(start -0.67945 0.3048)
			(end -0.120396 0.3048)
			(stroke
				(width 0.1)
				(type default)
			)
			(layer "B.Fab")
		)
		(fp_line
			(start -0.12065 -0.3048)
			(end -0.67945 -0.3048)
			(stroke
				(width 0.1)
				(type default)
			)
			(layer "B.Fab")
		)
		(fp_line
			(start -0.12065 -0.2794)
			(end -0.12065 -0.3048)
			(stroke
				(width 0.1)
				(type default)
			)
			(layer "B.Fab")
		)
		(fp_line
			(start -0.120396 0.2794)
			(end 0.12065 0.2794)
			(stroke
				(width 0.1)
				(type default)
			)
			(layer "B.Fab")
		)
		(fp_line
			(start -0.120396 0.3048)
			(end -0.120396 0.2794)
			(stroke
				(width 0.1)
				(type default)
			)
			(layer "B.Fab")
		)
		(fp_line
			(start 0.12065 -0.305054)
			(end 0.12065 -0.2794)
			(stroke
				(width 0.1)
				(type default)
			)
			(layer "B.Fab")
		)
		(fp_line
			(start 0.12065 -0.2794)
			(end -0.12065 -0.2794)
			(stroke
				(width 0.1)
				(type default)
			)
			(layer "B.Fab")
		)
		(fp_line
			(start 0.12065 0.2794)
			(end 0.12065 0.3048)
			(stroke
				(width 0.1)
				(type default)
			)
			(layer "B.Fab")
		)
		(fp_line
			(start 0.12065 0.3048)
			(end 0.67945 0.3048)
			(stroke
				(width 0.1)
				(type default)
			)
			(layer "B.Fab")
		)
		(fp_line
			(start 0.67945 -0.305054)
			(end 0.12065 -0.305054)
			(stroke
				(width 0.1)
				(type default)
			)
			(layer "B.Fab")
		)
		(fp_line
			(start 0.67945 0.3048)
			(end 0.67945 -0.305054)
			(stroke
				(width 0.1)
				(type default)
			)
			(layer "B.Fab")
		)
		(pad "1" smd circle
			(at 0.40005 0 180)
			(size 0 0)
			(layers "B.Cu" "B.Mask" "B.Paste")
			(net "P0V9_RETIMER_CPU0_EN")
		)
		(pad "2" smd circle
			(at -0.40005 0 180)
			(size 0 0)
			(layers "B.Cu" "B.Mask" "B.Paste")
			(net "P0V9_RETIMER_CPU0_EN_R2")
		)
	)
	(footprint ""
		(layer "B.Cu")
		(at 307.368194 -192.660016)
		(property "Reference" "C89"
			(at 0 0 0)
			(layer "B.SilkS")
			(hide yes)
			(effects
				(font
					(size 1.27 1.27)
				)
				(justify mirror)
			)
		)
		(property "Value" ""
			(at 0 0 0)
			(layer "B.Fab")
			(effects
				(font
					(size 1.27 1.27)
				)
				(justify mirror)
			)
		)
		(duplicate_pad_numbers_are_jumpers no)
		(fp_line
			(start -1.524 -0.762)
			(end -1.524 0.762)
			(stroke
				(width 0.1524)
				(type default)
			)
			(layer "B.SilkS")
		)
		(fp_line
			(start -1.524 0.762)
			(end 1.524 0.762)
			(stroke
				(width 0.1524)
				(type default)
			)
			(layer "B.SilkS")
		)
		(fp_line
			(start 1.524 -0.762)
			(end -1.524 -0.762)
			(stroke
				(width 0.1524)
				(type default)
			)
			(layer "B.SilkS")
		)
		(fp_line
			(start 1.524 0.762)
			(end 1.524 -0.762)
			(stroke
				(width 0.1524)
				(type default)
			)
			(layer "B.SilkS")
		)
		(fp_line
			(start -1.1049 -0.724916)
			(end 1.1049 -0.724916)
			(stroke
				(width 0.1)
				(type default)
			)
			(layer "B.Fab")
		)
		(fp_line
			(start -1.1049 0.724916)
			(end -1.1049 -0.724916)
			(stroke
				(width 0.1)
				(type default)
			)
			(layer "B.Fab")
		)
		(fp_line
			(start 1.1049 -0.724916)
			(end 1.1049 0.724916)
			(stroke
				(width 0.1)
				(type default)
			)
			(layer "B.Fab")
		)
		(fp_line
			(start 1.1049 0.724916)
			(end -1.1049 0.724916)
			(stroke
				(width 0.1)
				(type default)
			)
			(layer "B.Fab")
		)
		(pad "1" smd rect
			(at 0.889 0)
			(size 1.016 1.27)
			(layers "B.Cu" "B.Mask" "B.Paste")
			(net "P12V_MEM_CPU0")
		)
		(pad "2" smd rect
			(at -0.889 0)
			(size 1.016 1.27)
			(layers "B.Cu" "B.Mask" "B.Paste")
			(net "GND")
		)
	)
	(footprint ""
		(layer "B.Cu")
		(at 411.546294 -396.393162 -90)
		(property "Reference" "C673"
			(at 0 0 90)
			(layer "B.SilkS")
			(hide yes)
			(effects
				(font
					(size 1.27 1.27)
				)
				(justify mirror)
			)
		)
		(property "Value" ""
			(at 0 0 90)
			(layer "B.Fab")
			(effects
				(font
					(size 1.27 1.27)
				)
				(justify mirror)
			)
		)
		(duplicate_pad_numbers_are_jumpers no)
		(fp_line
			(start -0.299974 0.150114)
			(end 0.299974 0.150114)
			(stroke
				(width 0.1)
				(type default)
			)
			(layer "B.Fab")
		)
		(fp_line
			(start 0.299974 0.150114)
			(end 0.299974 -0.150114)
			(stroke
				(width 0.1)
				(type default)
			)
			(layer "B.Fab")
		)
		(fp_line
			(start -0.299974 -0.150114)
			(end -0.299974 0.150114)
			(stroke
				(width 0.1)
				(type default)
			)
			(layer "B.Fab")
		)
		(fp_line
			(start 0.299974 -0.150114)
			(end -0.299974 -0.150114)
			(stroke
				(width 0.1)
				(type default)
			)
			(layer "B.Fab")
		)
		(pad "1" smd rect
			(at 0.2667 0 90)
			(size 0.3048 0.381)
			(layers "B.Cu" "B.Mask" "B.Paste")
			(net "P1V8_CPU0_RT2_1A")
		)
		(pad "2" smd rect
			(at -0.2667 0 90)
			(size 0.3048 0.381)
			(layers "B.Cu" "B.Mask" "B.Paste")
			(net "GND")
		)
	)
	(footprint ""
		(layer "B.Cu")
		(at 7.62 -383.032 -90)
		(property "Reference" "PR6625"
			(at 0 0 90)
			(layer "B.SilkS")
			(hide yes)
			(effects
				(font
					(size 1.27 1.27)
				)
				(justify mirror)
			)
		)
		(property "Value" ""
			(at 0 0 90)
			(layer "B.Fab")
			(effects
				(font
					(size 1.27 1.27)
				)
				(justify mirror)
			)
		)
		(duplicate_pad_numbers_are_jumpers no)
		(fp_line
			(start -1.2954 0.5842)
			(end 1.2954 0.5842)
			(stroke
				(width 0.1524)
				(type default)
			)
			(layer "B.SilkS")
		)
		(fp_line
			(start 1.2954 0.5842)
			(end 1.2954 -0.5842)
			(stroke
				(width 0.1524)
				(type default)
			)
			(layer "B.SilkS")
		)
		(fp_line
			(start -1.2954 -0.5842)
			(end -1.2954 0.5842)
			(stroke
				(width 0.1524)
				(type default)
			)
			(layer "B.SilkS")
		)
		(fp_line
			(start 1.2954 -0.5842)
			(end -1.2954 -0.5842)
			(stroke
				(width 0.1524)
				(type default)
			)
			(layer "B.SilkS")
		)
		(fp_line
			(start -0.8636 0.4572)
			(end 0.8636 0.4572)
			(stroke
				(width 0.1)
				(type default)
			)
			(layer "B.Fab")
		)
		(fp_line
			(start 0.8636 0.4572)
			(end 0.8636 0.4318)
			(stroke
				(width 0.1)
				(type default)
			)
			(layer "B.Fab")
		)
		(fp_line
			(start 0.8636 0.4318)
			(end 0.8636 0.4064)
			(stroke
				(width 0.1)
				(type default)
			)
			(layer "B.Fab")
		)
		(fp_line
			(start -1.1938 0.4064)
			(end -0.8636 0.4064)
			(stroke
				(width 0.1)
				(type default)
			)
			(layer "B.Fab")
		)
		(fp_line
			(start -0.8636 0.4064)
			(end -0.8636 0.4572)
			(stroke
				(width 0.1)
				(type default)
			)
			(layer "B.Fab")
		)
		(fp_line
			(start 0.8636 0.4064)
			(end 1.1938 0.4064)
			(stroke
				(width 0.1)
				(type default)
			)
			(layer "B.Fab")
		)
		(fp_line
			(start 1.1938 0.4064)
			(end 1.1938 -0.406654)
			(stroke
				(width 0.1)
				(type default)
			)
			(layer "B.Fab")
		)
		(fp_line
			(start -1.1938 -0.406654)
			(end -1.1938 0.4064)
			(stroke
				(width 0.1)
				(type default)
			)
			(layer "B.Fab")
		)
		(fp_line
			(start -0.8636 -0.406654)
			(end -1.1938 -0.406654)
			(stroke
				(width 0.1)
				(type default)
			)
			(layer "B.Fab")
		)
		(fp_line
			(start 0.8636 -0.406654)
			(end 0.8636 -0.4572)
			(stroke
				(width 0.1)
				(type default)
			)
			(layer "B.Fab")
		)
		(fp_line
			(start 1.1938 -0.406654)
			(end 0.8636 -0.406654)
			(stroke
				(width 0.1)
				(type default)
			)
			(layer "B.Fab")
		)
		(fp_line
			(start -0.8636 -0.4572)
			(end -0.8636 -0.406654)
			(stroke
				(width 0.1)
				(type default)
			)
			(layer "B.Fab")
		)
		(fp_line
			(start 0.8636 -0.4572)
			(end -0.8636 -0.4572)
			(stroke
				(width 0.1)
				(type default)
			)
			(layer "B.Fab")
		)
		(pad "1" smd rect
			(at 0.7366 0 180)
			(size 0.7112 0.8128)
			(layers "B.Cu" "B.Mask" "B.Paste")
			(net "P0V9_CPU1_RT_2D")
		)
		(pad "2" smd rect
			(at -0.7366 0 180)
			(size 0.7112 0.8128)
			(layers "B.Cu" "B.Mask" "B.Paste")
			(net "GND")
		)
	)
	(footprint ""
		(layer "B.Cu")
		(at 347.624908 -169.787062 90)
		(property "Reference" "PC500_1"
			(at 0 0 90)
			(layer "B.SilkS")
			(hide yes)
			(effects
				(font
					(size 1.27 1.27)
				)
				(justify mirror)
			)
		)
		(property "Value" ""
			(at 0 0 90)
			(layer "B.Fab")
			(effects
				(font
					(size 1.27 1.27)
				)
				(justify mirror)
			)
		)
		(duplicate_pad_numbers_are_jumpers no)
		(fp_line
			(start 1.524 -0.762)
			(end -1.524 -0.762)
			(stroke
				(width 0.1524)
				(type default)
			)
			(layer "B.SilkS")
		)
		(fp_line
			(start -1.524 -0.762)
			(end -1.524 0.762)
			(stroke
				(width 0.1524)
				(type default)
			)
			(layer "B.SilkS")
		)
		(fp_line
			(start 1.524 0.762)
			(end 1.524 -0.762)
			(stroke
				(width 0.1524)
				(type default)
			)
			(layer "B.SilkS")
		)
		(fp_line
			(start -1.524 0.762)
			(end 1.524 0.762)
			(stroke
				(width 0.1524)
				(type default)
			)
			(layer "B.SilkS")
		)
		(fp_line
			(start 1.1049 -0.724916)
			(end 1.1049 0.724916)
			(stroke
				(width 0.1)
				(type default)
			)
			(layer "B.Fab")
		)
		(fp_line
			(start -1.1049 -0.724916)
			(end 1.1049 -0.724916)
			(stroke
				(width 0.1)
				(type default)
			)
			(layer "B.Fab")
		)
		(fp_line
			(start 1.1049 0.724916)
			(end -1.1049 0.724916)
			(stroke
				(width 0.1)
				(type default)
			)
			(layer "B.Fab")
		)
		(fp_line
			(start -1.1049 0.724916)
			(end -1.1049 -0.724916)
			(stroke
				(width 0.1)
				(type default)
			)
			(layer "B.Fab")
		)
		(pad "1" smd rect
			(at 0.889 0 90)
			(size 1.016 1.27)
			(layers "B.Cu" "B.Mask" "B.Paste")
			(net "PVDDCR_CPU0_P0")
		)
		(pad "2" smd rect
			(at -0.889 0 90)
			(size 1.016 1.27)
			(layers "B.Cu" "B.Mask" "B.Paste")
			(net "GND")
		)
	)
)
